(kicad_pcb
	(version 20241229)
	(generator "pcbnew")
	(generator_version "9.0")
	(general
		(thickness 1.294)
		(legacy_teardrops no)
	)
	(paper "A3")
	(title_block
		(title "Kintex 410T devboard")
		(date "2024-04-03")
		(rev "1.1.2")
		(comment 9 "footprints 294-297 of 975")
	)
	(layers
		(0 "F.Cu" mixed)
		(4 "In1.Cu" power)
		(6 "In2.Cu" power)
		(8 "In3.Cu" mixed)
		(10 "In4.Cu" power)
		(12 "In5.Cu" mixed)
		(14 "In6.Cu" power)
		(16 "In7.Cu" mixed)
		(18 "In8.Cu" power)
		(2 "B.Cu" mixed)
		(9 "F.Adhes" user "F.Adhesive")
		(11 "B.Adhes" user "B.Adhesive")
		(13 "F.Paste" user)
		(15 "B.Paste" user)
		(5 "F.SilkS" user "F.Silkscreen")
		(7 "B.SilkS" user "B.Silkscreen")
		(1 "F.Mask" user)
		(3 "B.Mask" user)
		(17 "Dwgs.User" user "User.Drawings")
		(19 "Cmts.User" user "User.Comments")
		(21 "Eco1.User" user "User.Eco1")
		(23 "Eco2.User" user "User.Eco2")
		(25 "Edge.Cuts" user)
		(27 "Margin" user)
		(31 "F.CrtYd" user "F.Courtyard")
		(29 "B.CrtYd" user "B.Courtyard")
		(35 "F.Fab" user)
		(33 "B.Fab" user)
	)
	(footprint "antmicro-footprints:USB-C_Receptacle_GCT_USB4105-GF-A"
		(locked yes)
		(layer "F.Cu")
		(at 267.11 146 90)
		(property "Reference" "J13"
			(at -6.1 0.49 180)
			(layer "F.SilkS")
			(effects
				(font
					(size 0.7 0.7)
					(thickness 0.15)
				)
				(justify left bottom)
			)
		)
		(property "Value" "USB-C_GCT_USB4105-GF-A"
			(at 0 5 90)
			(layer "F.Fab")
			(effects
				(font
					(size 0.7 0.7)
					(thickness 0.15)
				)
				(justify left bottom)
			)
		)
		(property "Description" "USB-C (USB TYPE-C) USB 2.0 Receptacle Connector 24 (16+8 Dummy) Position Surface Mount, Right Angle"
			(at 0 0 90)
			(layer "F.Fab")
			(hide yes)
			(effects
				(font
					(size 1.27 1.27)
					(thickness 0.15)
				)
			)
		)
		(property "Author" "Antmicro"
			(at 413.11 -121.11 0)
			(layer "F.Fab")
			(hide yes)
			(effects
				(font
					(size 1 1)
					(thickness 0.15)
				)
			)
		)
		(property "License" "Apache-2.0"
			(at 413.11 -121.11 0)
			(layer "F.Fab")
			(hide yes)
			(effects
				(font
					(size 1 1)
					(thickness 0.15)
				)
			)
		)
		(property "MPN" "USB4105-GF-A"
			(at 413.11 -121.11 0)
			(layer "F.Fab")
			(hide yes)
			(effects
				(font
					(size 1 1)
					(thickness 0.15)
				)
			)
		)
		(property "Manufacturer" "GCT"
			(at 413.11 -121.11 0)
			(layer "F.Fab")
			(hide yes)
			(effects
				(font
					(size 1 1)
					(thickness 0.15)
				)
			)
		)
		(property "VSD_Class" "USB-C"
			(at 413.11 -121.11 0)
			(layer "F.Fab")
			(hide yes)
			(effects
				(font
					(size 1 1)
					(thickness 0.15)
				)
			)
		)
		(sheetname "USB PHY")
		(sheetfile "usb-phy.kicad_sch")
		(attr smd)
		(fp_line
			(start 4.788 -1.395)
			(end 4.788 -0.145)
			(stroke
				(width 0.15)
				(type solid)
			)
			(layer "F.SilkS")
		)
		(fp_line
			(start -4.79 -1.395)
			(end -4.79 -0.145)
			(stroke
				(width 0.15)
				(type solid)
			)
			(layer "F.SilkS")
		)
		(fp_line
			(start -4.79 2.575)
			(end -4.79 3.854)
			(stroke
				(width 0.15)
				(type solid)
			)
			(layer "F.SilkS")
		)
		(fp_line
			(start 4.788 3.854)
			(end 4.788 2.575)
			(stroke
				(width 0.15)
				(type solid)
			)
			(layer "F.SilkS")
		)
		(fp_line
			(start -4.79 3.854)
			(end 4.788 3.854)
			(stroke
				(width 0.15)
				(type solid)
			)
			(layer "F.SilkS")
		)
		(fp_circle
			(center -3.8 -4.27071)
			(end -3.75 -4.22071)
			(stroke
				(width 0.15)
				(type solid)
			)
			(fill yes)
			(layer "F.SilkS")
		)
		(fp_rect
			(start -5.1 -4.4)
			(end 5.1 3.9)
			(stroke
				(width 0.05)
				(type solid)
			)
			(fill no)
			(layer "F.CrtYd")
		)
		(fp_line
			(start 4.788 -3.676)
			(end 4.788 3.854)
			(stroke
				(width 0.15)
				(type solid)
			)
			(layer "F.Fab")
		)
		(fp_line
			(start -4.79 -3.676)
			(end 4.788 -3.676)
			(stroke
				(width 0.15)
				(type solid)
			)
			(layer "F.Fab")
		)
		(fp_line
			(start 4.788 3.854)
			(end -4.79 3.854)
			(stroke
				(width 0.15)
				(type solid)
			)
			(layer "F.Fab")
		)
		(fp_line
			(start -4.702 3.854)
			(end 4.788 3.854)
			(stroke
				(width 0.15)
				(type solid)
			)
			(layer "F.Fab")
		)
		(fp_line
			(start -4.79 3.854)
			(end -4.79 -3.676)
			(stroke
				(width 0.15)
				(type solid)
			)
			(layer "F.Fab")
		)
		(pad "" np_thru_hole circle
			(at -2.891 -2.426 90)
			(size 0.65 0.65)
			(drill 0.65)
			(layers "*.Cu" "*.Mask")
		)
		(pad "" np_thru_hole circle
			(at 2.89 -2.426 90)
			(size 0.65 0.65)
			(drill 0.65)
			(layers "*.Cu" "*.Mask")
		)
		(pad "A1" smd roundrect
			(at -3.202 -3.5 90)
			(size 0.6 1.15)
			(layers "F.Cu" "F.Mask" "F.Paste")
			(roundrect_rratio 0.25)
			(net 1 "GND")
			(pinfunction "GND")
			(pintype "power_in")
		)
		(pad "A4" smd roundrect
			(at -2.4 -3.5 90)
			(size 0.6 1.15)
			(layers "F.Cu" "F.Mask" "F.Paste")
			(roundrect_rratio 0.25)
			(net 704 "/Power supply/USB_DBG_PD.VBUS")
			(pinfunction "VBUS")
			(pintype "passive")
		)
		(pad "A5" smd roundrect
			(at -1.25 -3.5 90)
			(size 0.3 1.15)
			(layers "F.Cu" "F.Mask" "F.Paste")
			(roundrect_rratio 0.25)
			(net 837 "/Power supply/USB_DBG_PD.CC1")
			(pinfunction "CC_{1}")
			(pintype "bidirectional")
		)
		(pad "A6" smd roundrect
			(at -0.25 -3.5 90)
			(size 0.3 1.15)
			(layers "F.Cu" "F.Mask" "F.Paste")
			(roundrect_rratio 0.25)
			(net 838 "/USB PHY/USB_DBG_CONN_D+")
			(pinfunction "D_{A}+")
			(pintype "bidirectional")
		)
		(pad "A7" smd roundrect
			(at 0.248 -3.5 90)
			(size 0.3 1.15)
			(layers "F.Cu" "F.Mask" "F.Paste")
			(roundrect_rratio 0.25)
			(net 839 "/USB PHY/USB_DBG_CONN_D-")
			(pinfunction "D_{A}-")
			(pintype "bidirectional")
		)
		(pad "A8" smd roundrect
			(at 1.249 -3.5 90)
			(size 0.3 1.15)
			(layers "F.Cu" "F.Mask" "F.Paste")
			(roundrect_rratio 0.25)
			(net 32 "unconnected-(J13-SBU_{1}-PadA8)")
			(pinfunction "SBU_{1}")
			(pintype "bidirectional+no_connect")
		)
		(pad "A9" smd roundrect
			(at 2.398 -3.5 90)
			(size 0.6 1.15)
			(layers "F.Cu" "F.Mask" "F.Paste")
			(roundrect_rratio 0.25)
			(net 704 "/Power supply/USB_DBG_PD.VBUS")
			(pinfunction "VBUS")
			(pintype "passive")
		)
		(pad "A12" smd roundrect
			(at 3.2 -3.5 90)
			(size 0.6 1.15)
			(layers "F.Cu" "F.Mask" "F.Paste")
			(roundrect_rratio 0.25)
			(net 1 "GND")
			(pinfunction "GND")
			(pintype "passive")
		)
		(pad "B1" smd roundrect
			(at 3.2 -3.5 90)
			(size 0.6 1.15)
			(layers "F.Cu" "F.Mask" "F.Paste")
			(roundrect_rratio 0.25)
			(net 1 "GND")
			(pinfunction "GND")
			(pintype "passive")
		)
		(pad "B4" smd roundrect
			(at 2.398 -3.5 90)
			(size 0.6 1.15)
			(layers "F.Cu" "F.Mask" "F.Paste")
			(roundrect_rratio 0.25)
			(net 704 "/Power supply/USB_DBG_PD.VBUS")
			(pinfunction "VBUS")
			(pintype "passive")
		)
		(pad "B5" smd roundrect
			(at 1.749 -3.5 90)
			(size 0.3 1.15)
			(layers "F.Cu" "F.Mask" "F.Paste")
			(roundrect_rratio 0.25)
			(net 840 "/Power supply/USB_DBG_PD.CC2")
			(pinfunction "CC_{2}")
			(pintype "bidirectional")
		)
		(pad "B6" smd roundrect
			(at 0.748 -3.5 90)
			(size 0.3 1.15)
			(layers "F.Cu" "F.Mask" "F.Paste")
			(roundrect_rratio 0.25)
			(net 838 "/USB PHY/USB_DBG_CONN_D+")
			(pinfunction "D_{B}+")
			(pintype "bidirectional")
		)
		(pad "B7" smd roundrect
			(at -0.75 -3.5 90)
			(size 0.3 1.15)
			(layers "F.Cu" "F.Mask" "F.Paste")
			(roundrect_rratio 0.25)
			(net 839 "/USB PHY/USB_DBG_CONN_D-")
			(pinfunction "D_{B}-")
			(pintype "bidirectional")
		)
		(pad "B8" smd roundrect
			(at -1.75 -3.5 90)
			(size 0.3 1.15)
			(layers "F.Cu" "F.Mask" "F.Paste")
			(roundrect_rratio 0.25)
			(net 33 "unconnected-(J13-SBU_{2}-PadB8)")
			(pinfunction "SBU_{2}")
			(pintype "bidirectional+no_connect")
		)
		(pad "B9" smd roundrect
			(at -2.4 -3.5 90)
			(size 0.6 1.15)
			(layers "F.Cu" "F.Mask" "F.Paste")
			(roundrect_rratio 0.25)
			(net 704 "/Power supply/USB_DBG_PD.VBUS")
			(pinfunction "VBUS")
			(pintype "passive")
		)
		(pad "B12" smd roundrect
			(at -3.202 -3.5 90)
			(size 0.6 1.15)
			(layers "F.Cu" "F.Mask" "F.Paste")
			(roundrect_rratio 0.25)
			(net 1 "GND")
			(pinfunction "GND")
			(pintype "passive")
		)
		(pad "SH" thru_hole oval
			(at -4.321 -2.926 90)
			(size 1.05 2.1)
			(drill oval 0.6 1.7)
			(layers "*.Cu" "*.Mask")
			(remove_unused_layers no)
			(net 1 "GND")
			(pinfunction "SH")
			(pintype "passive")
		)
		(pad "SH" thru_hole oval
			(at -4.321 1.255 90)
			(size 1 2)
			(drill oval 0.6 1.4)
			(layers "*.Cu" "*.Mask")
			(remove_unused_layers no)
			(net 1 "GND")
			(pinfunction "SH")
			(pintype "passive")
		)
		(pad "SH" thru_hole oval
			(at 4.32 -2.926 90)
			(size 1.05 2.1)
			(drill oval 0.6 1.7)
			(layers "*.Cu" "*.Mask")
			(remove_unused_layers no)
			(net 1 "GND")
			(pinfunction "SH")
			(pintype "passive")
		)
		(pad "SH" thru_hole oval
			(at 4.32 1.255 90)
			(size 1 2)
			(drill oval 0.6 1.4)
			(layers "*.Cu" "*.Mask")
			(remove_unused_layers no)
			(net 1 "GND")
			(pinfunction "SH")
			(pintype "passive")
		)
	)
	(footprint "antmicro-footprints:R_0402_1005Metric"
		(layer "F.Cu")
		(at 264.7 135.6 90)
		(descr "Resistor SMD 0402")
		(tags "resistor SMD 0402")
		(property "Reference" "R152"
			(at 31.25 -29.85 180)
			(layer "F.SilkS")
			(effects
				(font
					(size 0.7 0.7)
					(thickness 0.15)
				)
				(justify left bottom)
			)
		)
		(property "Value" "R_330R_0402"
			(at 0 1.4 90)
			(layer "F.Fab")
			(effects
				(font
					(size 0.7 0.7)
					(thickness 0.15)
				)
				(justify left bottom)
			)
		)
		(property "Description" "SMD Chip Resistor, 330 ohm, ± 1%, 62.5 mW, 0402 [1005 Metric], Thick Film, General Purpose"
			(at 0 0 90)
			(layer "F.Fab")
			(hide yes)
			(effects
				(font
					(size 1.27 1.27)
					(thickness 0.15)
				)
			)
		)
		(property "Author" "Antmicro"
			(at 400.3 -129.1 0)
			(layer "F.Fab")
			(hide yes)
			(effects
				(font
					(size 1 1)
					(thickness 0.15)
				)
			)
		)
		(property "License" "Apache-2.0"
			(at 400.3 -129.1 0)
			(layer "F.Fab")
			(hide yes)
			(effects
				(font
					(size 1 1)
					(thickness 0.15)
				)
			)
		)
		(property "MPN" "CR0402-FX-3300GLF"
			(at 400.3 -129.1 0)
			(layer "F.Fab")
			(hide yes)
			(effects
				(font
					(size 1 1)
					(thickness 0.15)
				)
			)
		)
		(property "Manufacturer" "Bourns"
			(at 400.3 -129.1 0)
			(layer "F.Fab")
			(hide yes)
			(effects
				(font
					(size 1 1)
					(thickness 0.15)
				)
			)
		)
		(property "Tolerance" "1%"
			(at 400.3 -129.1 0)
			(layer "F.Fab")
			(hide yes)
			(effects
				(font
					(size 1 1)
					(thickness 0.15)
				)
			)
		)
		(property "Val" "330R"
			(at 400.3 -129.1 0)
			(layer "F.Fab")
			(hide yes)
			(effects
				(font
					(size 1 1)
					(thickness 0.15)
				)
			)
		)
		(sheetname "USB PHY")
		(sheetfile "usb-phy.kicad_sch")
		(attr smd)
		(fp_rect
			(start -0.925 -0.47)
			(end 0.925 0.47)
			(stroke
				(width 0.05)
				(type default)
			)
			(fill no)
			(layer "F.CrtYd")
		)
		(fp_rect
			(start -0.5 -0.25)
			(end 0.5 0.25)
			(stroke
				(width 0.15)
				(type solid)
			)
			(fill no)
			(layer "F.Fab")
		)
		(pad "1" smd roundrect
			(at -0.48 0 90)
			(size 0.59 0.64)
			(layers "F.Cu" "F.Mask" "F.Paste")
			(roundrect_rratio 0.25)
			(net 792 "Net-(D28-A)")
			(pintype "passive")
		)
		(pad "2" smd roundrect
			(at 0.48 0 90)
			(size 0.59 0.64)
			(layers "F.Cu" "F.Mask" "F.Paste")
			(roundrect_rratio 0.25)
			(net 914 "/USB PHY/LED_TX1")
			(pintype "passive")
		)
	)
	(footprint "antmicro-footprints:C_0402_1005Metric"
		(layer "F.Cu")
		(at 157.9 153.76 90)
		(descr "Capacitor SMD 0402")
		(tags "capacitor SMD 0402")
		(property "Reference" "C355"
			(at 0.8 0.35 90)
			(layer "F.SilkS")
			(effects
				(font
					(size 0.7 0.7)
					(thickness 0.15)
				)
				(justify left bottom)
			)
		)
		(property "Value" "C_10u_0402"
			(at 0 1.4 90)
			(layer "F.Fab")
			(effects
				(font
					(size 0.7 0.7)
					(thickness 0.15)
				)
				(justify left bottom)
			)
		)
		(property "Description" "SMD Multilayer Ceramic Capacitor, 10 µF, 6.3 V, 0402 [1005 Metric], ± 20%, X5R, CC Series"
			(at 0 0 90)
			(layer "F.Fab")
			(hide yes)
			(effects
				(font
					(size 1.27 1.27)
					(thickness 0.15)
				)
			)
		)
		(property "Author" "Antmicro"
			(at 311.66 -4.14 0)
			(layer "F.Fab")
			(hide yes)
			(effects
				(font
					(size 1 1)
					(thickness 0.15)
				)
			)
		)
		(property "Dielectric" ""
			(at 311.66 -4.14 0)
			(layer "F.Fab")
			(hide yes)
			(effects
				(font
					(size 1 1)
					(thickness 0.15)
				)
			)
		)
		(property "License" "Apache-2.0"
			(at 311.66 -4.14 0)
			(layer "F.Fab")
			(hide yes)
			(effects
				(font
					(size 1 1)
					(thickness 0.15)
				)
			)
		)
		(property "MPN" "CC0402MRX5R5BB106"
			(at 311.66 -4.14 0)
			(layer "F.Fab")
			(hide yes)
			(effects
				(font
					(size 1 1)
					(thickness 0.15)
				)
			)
		)
		(property "Manufacturer" "YAGEO"
			(at 311.66 -4.14 0)
			(layer "F.Fab")
			(hide yes)
			(effects
				(font
					(size 1 1)
					(thickness 0.15)
				)
			)
		)
		(property "Val" "10u"
			(at 311.66 -4.14 0)
			(layer "F.Fab")
			(hide yes)
			(effects
				(font
					(size 1 1)
					(thickness 0.15)
				)
			)
		)
		(property "Voltage" ""
			(at 311.66 -4.14 0)
			(layer "F.Fab")
			(hide yes)
			(effects
				(font
					(size 1 1)
					(thickness 0.15)
				)
			)
		)
		(sheetname "DC-DC Converters")
		(sheetfile "dc-dc.kicad_sch")
		(attr smd)
		(fp_rect
			(start -0.925 -0.47)
			(end 0.925 0.47)
			(stroke
				(width 0.05)
				(type default)
			)
			(fill no)
			(layer "F.CrtYd")
		)
		(fp_line
			(start 0.504 -0.25)
			(end 0.504 0.248)
			(stroke
				(width 0.15)
				(type solid)
			)
			(layer "F.Fab")
		)
		(fp_line
			(start -0.494 -0.25)
			(end 0.504 -0.25)
			(stroke
				(width 0.15)
				(type solid)
			)
			(layer "F.Fab")
		)
		(fp_line
			(start 0.504 0.248)
			(end -0.494 0.248)
			(stroke
				(width 0.15)
				(type solid)
			)
			(layer "F.Fab")
		)
		(fp_line
			(start -0.494 0.248)
			(end -0.494 -0.25)
			(stroke
				(width 0.15)
				(type solid)
			)
			(layer "F.Fab")
		)
		(pad "1" smd roundrect
			(at -0.48 0 90)
			(size 0.59 0.64)
			(layers "F.Cu" "F.Mask" "F.Paste")
			(roundrect_rratio 0.25)
			(net 1 "GND")
			(pintype "passive")
		)
		(pad "2" smd roundrect
			(at 0.48 0 90)
			(size 0.59 0.64)
			(layers "F.Cu" "F.Mask" "F.Paste")
			(roundrect_rratio 0.25)
			(net 750 "/DC-DC Converters/VDDR_VTT")
			(pintype "passive")
		)
	)
	(footprint "antmicro-footprints:R_0402_1005Metric"
		(layer "F.Cu")
		(at 225.025 119.5)
		(descr "Resistor SMD 0402")
		(tags "resistor SMD 0402")
		(property "Reference" "R77"
			(at -2.975 0.4 0)
			(layer "F.SilkS")
			(effects
				(font
					(size 0.7 0.7)
					(thickness 0.15)
				)
				(justify left bottom)
			)
		)
		(property "Value" "R_0R_0402"
			(at 0 1.4 0)
			(layer "F.Fab")
			(effects
				(font
					(size 0.7 0.7)
					(thickness 0.15)
				)
				(justify left bottom)
			)
		)
		(property "Description" "SMD Chip Resistor, Jumper, 0 ohm, 100 mW, 0402 [1005 Metric], Thick Film, General Purpose"
			(at 0 0 0)
			(layer "F.Fab")
			(hide yes)
			(effects
				(font
					(size 1.27 1.27)
					(thickness 0.15)
				)
			)
		)
		(property "Author" "Antmicro"
			(at 0 0 0)
			(layer "F.Fab")
			(hide yes)
			(effects
				(font
					(size 1 1)
					(thickness 0.15)
				)
			)
		)
		(property "Current" "1A"
			(at 0 0 0)
			(layer "F.Fab")
			(hide yes)
			(effects
				(font
					(size 1 1)
					(thickness 0.15)
				)
			)
		)
		(property "License" "Apache-2.0"
			(at 0 0 0)
			(layer "F.Fab")
			(hide yes)
			(effects
				(font
					(size 1 1)
					(thickness 0.15)
				)
			)
		)
		(property "MPN" "ERJ2GE0R00X"
			(at 0 0 0)
			(layer "F.Fab")
			(hide yes)
			(effects
				(font
					(size 1 1)
					(thickness 0.15)
				)
			)
		)
		(property "Manufacturer" "Panasonic"
			(at 0 0 0)
			(layer "F.Fab")
			(hide yes)
			(effects
				(font
					(size 1 1)
					(thickness 0.15)
				)
			)
		)
		(property "Tolerance" ""
			(at 0 0 0)
			(layer "F.Fab")
			(hide yes)
			(effects
				(font
					(size 1 1)
					(thickness 0.15)
				)
			)
		)
		(property "Val" "0R"
			(at 0 0 0)
			(layer "F.Fab")
			(hide yes)
			(effects
				(font
					(size 1 1)
					(thickness 0.15)
				)
			)
		)
		(sheetname "SPI Flash + SD Card")
		(sheetfile "spi-flash.kicad_sch")
		(attr smd)
		(fp_rect
			(start -0.925 -0.47)
			(end 0.925 0.47)
			(stroke
				(width 0.05)
				(type default)
			)
			(fill no)
			(layer "F.CrtYd")
		)
		(fp_rect
			(start -0.5 -0.25)
			(end 0.5 0.25)
			(stroke
				(width 0.15)
				(type solid)
			)
			(fill no)
			(layer "F.Fab")
		)
		(pad "1" smd roundrect
			(at -0.48 0)
			(size 0.59 0.64)
			(layers "F.Cu" "F.Mask" "F.Paste")
			(roundrect_rratio 0.25)
			(net 43 "/FPGA Bank 14 & 15/SYSTEM_FLASH.DQ1")
			(pintype "passive")
		)
		(pad "2" smd roundrect
			(at 0.48 0)
			(size 0.59 0.64)
			(layers "F.Cu" "F.Mask" "F.Paste")
			(roundrect_rratio 0.25)
			(net 897 "/SPI Flash + SD Card/SYSTEM_FLASH_DQ1")
			(pintype "passive")
		)
	)
)
